# BASEBOARD_FAB2 (Tioga Pass) — schematic netlist excerpt (pin names and nets, part order shuffled) for the footprints in the layout excerpt that follows; sources: Cadence DE-HDL packaged netlist, KiCad conversion of Wiwynn_Tioga_Pass_MB.brd

R8B30  RES  1.00K 1% CHIP  pkg 0402  page 133 : A = P3V3_STBY ; B = FM_XRC_READY_N
R9F68  RES  0.0 5% EMPTY  pkg 0402  page 158 : A = SP2_BMC_CM_UART_RX_R ; B = SP2_BMC_CM_UART_RX
C4D5  CAP  0.22UF 16V 10% X7R  pkg 0402  page 203 : A = P5V_STBY ; B = GND

(kicad_pcb
	(version 20260206)
	(generator "pcbnew")
	(generator_version "10.0")
	(general
		(thickness 1.6)
		(legacy_teardrops no)
	)
	(paper "A4")
	(title_block
		(title "Wiwynn_Tioga_Pass_MB.brd")
		(comment 1 "Tioga Pass / footprints 544-546 of 4770")
	)
	(layers
		(0 "F.Cu" signal "TOP")
		(4 "In1.Cu" signal "L2GND")
		(6 "In2.Cu" signal "L3")
		(8 "In3.Cu" signal "L4GND")
		(10 "In4.Cu" signal "L5")
		(12 "In5.Cu" signal "L6GND")
		(14 "In6.Cu" signal "L7VCC")
		(16 "In7.Cu" signal "L8VCC")
		(18 "In8.Cu" signal "L9GND")
		(20 "In9.Cu" signal "L10")
		(22 "In10.Cu" signal "L11GND")
		(24 "In11.Cu" signal "L12")
		(26 "In12.Cu" signal "L13GND")
		(2 "B.Cu" signal "BOTTOM")
		(9 "F.Adhes" user "F.Adhesive")
		(11 "B.Adhes" user "B.Adhesive")
		(13 "F.Paste" user "Package Geometry/Pastemask Top")
		(15 "B.Paste" user "Package Geometry/Pastemask Bottom")
		(5 "F.SilkS" user "Ref Des/Silkscreen Top")
		(7 "B.SilkS" user "Ref Des/Silkscreen Bottom")
		(1 "F.Mask" user "Board Geometry/Soldermask Top")
		(3 "B.Mask" user "Board Geometry/Soldermask Bottom")
		(17 "Dwgs.User" user "User.Drawings")
		(19 "Cmts.User" user "User.Comments")
		(21 "Eco1.User" user "User.Eco1")
		(23 "Eco2.User" user "User.Eco2")
		(25 "Edge.Cuts" user "Board Geometry/Outline")
		(27 "Margin" user)
		(31 "F.CrtYd" user "Package Geometry/Place Bound Top")
		(29 "B.CrtYd" user "Package Geometry/Place Bound Bottom")
		(35 "F.Fab" user "Ref Des/Assembly Top")
		(33 "B.Fab" user "Ref Des/Assembly Bottom")
	)
	(footprint ""
		(layer "F.Cu")
		(at 408.7495 -113.284 -90)
		(property "Reference" "R8B30"
			(at 0 0 270)
			(layer "F.SilkS")
			(hide yes)
			(effects
				(font
					(size 1.27 1.27)
				)
			)
		)
		(property "Value" ""
			(at 0 0 270)
			(layer "F.Fab")
			(effects
				(font
					(size 1.27 1.27)
				)
			)
		)
		(duplicate_pad_numbers_are_jumpers no)
		(fp_poly
			(pts
				(xy -0.2794 -0.1016) (xy 0.2794 -0.1016) (xy 0.2794 0.9906) (xy -0.2794 0.9906)
			)
			(stroke
				(width 0)
				(type default)
			)
			(fill no)
			(layer "F.CrtYd")
		)
		(fp_line
			(start -0.2794 0.9906)
			(end 0.2794 0.9906)
			(stroke
				(width 0.1)
				(type default)
			)
			(layer "F.Fab")
		)
		(fp_line
			(start 0.2794 0.9906)
			(end 0.2794 -0.1016)
			(stroke
				(width 0.1)
				(type default)
			)
			(layer "F.Fab")
		)
		(fp_line
			(start -0.2794 -0.1016)
			(end -0.2794 0.9906)
			(stroke
				(width 0.1)
				(type default)
			)
			(layer "F.Fab")
		)
		(fp_line
			(start 0.2794 -0.1016)
			(end -0.2794 -0.1016)
			(stroke
				(width 0.1)
				(type default)
			)
			(layer "F.Fab")
		)
		(pad "1" smd rect
			(at 0 0 270)
			(size 0.508 0.508)
			(layers "F.Cu" "F.Mask" "F.Paste")
			(net "P3V3_STBY")
		)
		(pad "2" smd rect
			(at 0 0.889 270)
			(size 0.508 0.508)
			(layers "F.Cu" "F.Mask" "F.Paste")
			(net "FM_XRC_READY_N")
		)
		(zone
			(layer "F.Cu")
			(hatch none 0.5)
			(connect_pads
				(clearance 0)
			)
			(min_thickness 0.25)
			(keepout
				(tracks not_allowed)
				(vias allowed)
				(pads allowed)
				(copperpour not_allowed)
				(footprints allowed)
			)
			(placement
				(enabled no)
				(sheetname "")
			)
			(fill
				(thermal_gap 0.5)
				(thermal_bridge_width 0.5)
				(island_removal_mode 0)
			)
			(polygon
				(pts
					(xy 408.1145 -113.538) (xy 408.1145 -113.03) (xy 408.4955 -113.03) (xy 408.4955 -113.538)
				)
			)
		)
		(zone
			(layer "F.Cu")
			(hatch none 0.5)
			(connect_pads
				(clearance 0)
			)
			(min_thickness 0.25)
			(keepout
				(tracks allowed)
				(vias not_allowed)
				(pads allowed)
				(copperpour not_allowed)
				(footprints allowed)
			)
			(placement
				(enabled no)
				(sheetname "")
			)
			(fill
				(thermal_gap 0.5)
				(thermal_bridge_width 0.5)
				(island_removal_mode 0)
			)
			(polygon
				(pts
					(xy 408.4955 -113.538) (xy 408.4955 -113.03) (xy 408.1145 -113.03) (xy 408.1145 -113.538)
				)
			)
		)
	)
	(footprint ""
		(layer "F.Cu")
		(at 486.687876 -27.227784)
		(property "Reference" "R9F68"
			(at 0 0 0)
			(layer "F.SilkS")
			(hide yes)
			(effects
				(font
					(size 1.27 1.27)
				)
			)
		)
		(property "Value" ""
			(at 0 0 0)
			(layer "F.Fab")
			(effects
				(font
					(size 1.27 1.27)
				)
			)
		)
		(duplicate_pad_numbers_are_jumpers no)
		(fp_poly
			(pts
				(xy -0.2794 -0.1016) (xy 0.2794 -0.1016) (xy 0.2794 0.9906) (xy -0.2794 0.9906)
			)
			(stroke
				(width 0)
				(type default)
			)
			(fill no)
			(layer "F.CrtYd")
		)
		(fp_line
			(start -0.2794 -0.1016)
			(end -0.2794 0.9906)
			(stroke
				(width 0.1)
				(type default)
			)
			(layer "F.Fab")
		)
		(fp_line
			(start -0.2794 0.9906)
			(end 0.2794 0.9906)
			(stroke
				(width 0.1)
				(type default)
			)
			(layer "F.Fab")
		)
		(fp_line
			(start 0.2794 -0.1016)
			(end -0.2794 -0.1016)
			(stroke
				(width 0.1)
				(type default)
			)
			(layer "F.Fab")
		)
		(fp_line
			(start 0.2794 0.9906)
			(end 0.2794 -0.1016)
			(stroke
				(width 0.1)
				(type default)
			)
			(layer "F.Fab")
		)
		(pad "1" smd rect
			(at 0 0)
			(size 0.508 0.508)
			(layers "F.Cu" "F.Mask" "F.Paste")
			(net "SP2_BMC_CM_UART_RX_R")
		)
		(pad "2" smd rect
			(at 0 0.889)
			(size 0.508 0.508)
			(layers "F.Cu" "F.Mask" "F.Paste")
			(net "SP2_BMC_CM_UART_RX")
		)
		(zone
			(layer "F.Cu")
			(hatch none 0.5)
			(connect_pads
				(clearance 0)
			)
			(min_thickness 0.25)
			(keepout
				(tracks allowed)
				(vias not_allowed)
				(pads allowed)
				(copperpour not_allowed)
				(footprints allowed)
			)
			(placement
				(enabled no)
				(sheetname "")
			)
			(fill
				(thermal_gap 0.5)
				(thermal_bridge_width 0.5)
				(island_removal_mode 0)
			)
			(polygon
				(pts
					(xy 486.433876 -26.973784) (xy 486.941876 -26.973784) (xy 486.941876 -26.592784) (xy 486.433876 -26.592784)
				)
			)
		)
		(zone
			(layer "F.Cu")
			(hatch none 0.5)
			(connect_pads
				(clearance 0)
			)
			(min_thickness 0.25)
			(keepout
				(tracks not_allowed)
				(vias allowed)
				(pads allowed)
				(copperpour not_allowed)
				(footprints allowed)
			)
			(placement
				(enabled no)
				(sheetname "")
			)
			(fill
				(thermal_gap 0.5)
				(thermal_bridge_width 0.5)
				(island_removal_mode 0)
			)
			(polygon
				(pts
					(xy 486.433876 -26.592784) (xy 486.941876 -26.592784) (xy 486.941876 -26.973784) (xy 486.433876 -26.973784)
				)
			)
		)
	)
	(footprint ""
		(layer "F.Cu")
		(at 198.065644 -77.513942 90)
		(property "Reference" "C4D5"
			(at -0.8382 -0.67818 90)
			(unlocked yes)
			(layer "F.SilkS")
			(effects
				(font
					(size 0.4064 0.254)
					(thickness 0.1524)
				)
				(justify left)
			)
		)
		(property "Value" ""
			(at 0 0 90)
			(layer "F.Fab")
			(effects
				(font
					(size 1.27 1.27)
				)
			)
		)
		(duplicate_pad_numbers_are_jumpers no)
		(fp_poly
			(pts
				(xy 0.3048 -0.1016) (xy 0.3048 0.9906) (xy -0.3048 0.9906) (xy -0.3048 -0.1016)
			)
			(stroke
				(width 0)
				(type default)
			)
			(fill no)
			(layer "F.CrtYd")
		)
		(fp_line
			(start 0.3048 -0.1016)
			(end -0.3048 -0.1016)
			(stroke
				(width 0.1)
				(type default)
			)
			(layer "F.Fab")
		)
		(fp_line
			(start -0.3048 -0.1016)
			(end -0.3048 0.9906)
			(stroke
				(width 0.1)
				(type default)
			)
			(layer "F.Fab")
		)
		(fp_line
			(start 0.3048 0.9906)
			(end 0.3048 -0.1016)
			(stroke
				(width 0.1)
				(type default)
			)
			(layer "F.Fab")
		)
		(fp_line
			(start -0.3048 0.9906)
			(end 0.3048 0.9906)
			(stroke
				(width 0.1)
				(type default)
			)
			(layer "F.Fab")
		)
		(pad "1" smd rect
			(at 0 0 90)
			(size 0.508 0.508)
			(layers "F.Cu" "F.Mask" "F.Paste")
			(net "P5V_STBY")
		)
		(pad "2" smd rect
			(at 0 0.889 90)
			(size 0.508 0.508)
			(layers "F.Cu" "F.Mask" "F.Paste")
			(net "GND")
		)
		(zone
			(layer "F.Cu")
			(hatch none 0.5)
			(connect_pads
				(clearance 0)
			)
			(min_thickness 0.25)
			(keepout
				(tracks allowed)
				(vias not_allowed)
				(pads allowed)
				(copperpour not_allowed)
				(footprints allowed)
			)
			(placement
				(enabled no)
				(sheetname "")
			)
			(fill
				(thermal_gap 0.5)
				(thermal_bridge_width 0.5)
				(island_removal_mode 0)
			)
			(polygon
				(pts
					(xy 198.319644 -77.259942) (xy 198.319644 -77.767942) (xy 198.700644 -77.767942) (xy 198.700644 -77.259942)
				)
			)
		)
		(zone
			(layer "F.Cu")
			(hatch none 0.5)
			(connect_pads
				(clearance 0)
			)
			(min_thickness 0.25)
			(keepout
				(tracks not_allowed)
				(vias allowed)
				(pads allowed)
				(copperpour not_allowed)
				(footprints allowed)
			)
			(placement
				(enabled no)
				(sheetname "")
			)
			(fill
				(thermal_gap 0.5)
				(thermal_bridge_width 0.5)
				(island_removal_mode 0)
			)
			(polygon
				(pts
					(xy 198.700644 -77.259942) (xy 198.700644 -77.767942) (xy 198.319644 -77.767942) (xy 198.319644 -77.259942)
				)
			)
		)
	)
)
